(kicad_pcb
	(version 20260206)
	(generator "pcbnew")
	(generator_version "10.0")
	(general
		(thickness 1.6)
		(legacy_teardrops no)
	)
	(paper "A4")
	(title_block
		(title "peb — Lightning_PEB_BRD.brd")
		(comment 1 "Lightning (Wiwynn / Facebook NVMe JBOF) / footprints 169-176 of 2563")
	)
	(layers
		(0 "F.Cu" signal "TOP")
		(4 "In1.Cu" signal "L2GND")
		(6 "In2.Cu" signal "L3")
		(8 "In3.Cu" signal "L4VCC")
		(10 "In4.Cu" signal "L5VCC")
		(12 "In5.Cu" signal "L6")
		(14 "In6.Cu" signal "L7GND")
		(2 "B.Cu" signal "BOTTOM")
		(9 "F.Adhes" user "F.Adhesive")
		(11 "B.Adhes" user "B.Adhesive")
		(13 "F.Paste" user "Package Geometry/Pastemask Top")
		(15 "B.Paste" user "Package Geometry/Pastemask Bottom")
		(5 "F.SilkS" user "Ref Des/Silkscreen Top")
		(7 "B.SilkS" user "Ref Des/Silkscreen Bottom")
		(1 "F.Mask" user "Board Geometry/Soldermask Top")
		(3 "B.Mask" user "Board Geometry/Soldermask Bottom")
		(17 "Dwgs.User" user "User.Drawings")
		(19 "Cmts.User" user "User.Comments")
		(21 "Eco1.User" user "User.Eco1")
		(23 "Eco2.User" user "User.Eco2")
		(25 "Edge.Cuts" user "Board Geometry/Outline")
		(27 "Margin" user)
		(31 "F.CrtYd" user "Package Geometry/Place Bound Top")
		(29 "B.CrtYd" user "Package Geometry/Place Bound Bottom")
		(35 "F.Fab" user "Ref Des/Assembly Top")
		(33 "B.Fab" user "Ref Des/Assembly Bottom")
	)
	(footprint ""
		(layer "F.Cu")
		(at 196.9262 -34.3408 90)
		(property "Reference" "R791"
			(at 0 0 90)
			(layer "F.SilkS")
			(hide yes)
			(effects
				(font
					(size 1.27 1.27)
				)
			)
		)
		(property "Value" "4K7R2F-GP"
			(at 0.064008 -3.993896 90)
			(unlocked yes)
			(layer "F.Fab")
			(hide yes)
			(effects
				(font
					(size 1.016 1.016)
					(thickness 0.1524)
				)
			)
		)
		(property "Device Type" "R402H16"
			(at 0.064008 -5.517896 90)
			(unlocked yes)
			(layer "F.Fab")
			(hide yes)
			(effects
				(font
					(size 1.016 1.016)
					(thickness 0.1524)
				)
			)
		)
		(duplicate_pad_numbers_are_jumpers no)
		(fp_line
			(start 0.508 -0.9398)
			(end -0.508 -0.9398)
			(stroke
				(width 0.1524)
				(type default)
			)
			(layer "F.SilkS")
		)
		(fp_line
			(start -0.508 -0.9398)
			(end -0.508 0.9398)
			(stroke
				(width 0.1524)
				(type default)
			)
			(layer "F.SilkS")
		)
		(fp_rect
			(start -0.508 0.9398)
			(end 0.508 -0.9398)
			(stroke
				(width 0)
				(type default)
			)
			(fill no)
			(layer "F.CrtYd")
		)
		(fp_rect
			(start -0.508 0.9398)
			(end 0.508 -0.9398)
			(stroke
				(width 0)
				(type default)
			)
			(fill no)
			(layer "F.Fab")
		)
		(pad "1" smd custom
			(at 0 -0.4445 90)
			(size 0.1397 0.1397)
			(layers "F.Cu" "F.Mask" "F.Paste")
			(net "GND")
			(options
				(clearance outline)
				(anchor circle)
			)
			(primitives
				(gr_poly
					(pts
						(arc
							(start -0.1778 -0.2794)
							(mid -0.249642 -0.249642)
							(end -0.2794 -0.1778)
						)
						(arc
							(start -0.2794 0.1778)
							(mid -0.249642 0.249642)
							(end -0.1778 0.2794)
						)
						(arc
							(start 0.1778 0.2794)
							(mid 0.249642 0.249642)
							(end 0.2794 0.1778)
						)
						(arc
							(start 0.2794 -0.1778)
							(mid 0.249642 -0.249642)
							(end 0.1778 -0.2794)
						)
					)
					(width 0)
					(fill yes)
				)
			)
		)
		(pad "2" smd custom
			(at 0 0.4445 90)
			(size 0.1397 0.1397)
			(layers "F.Cu" "F.Mask" "F.Paste")
			(net "U55_A0")
			(options
				(clearance outline)
				(anchor circle)
			)
			(primitives
				(gr_poly
					(pts
						(arc
							(start -0.1778 -0.2794)
							(mid -0.249642 -0.249642)
							(end -0.2794 -0.1778)
						)
						(arc
							(start -0.2794 0.1778)
							(mid -0.249642 0.249642)
							(end -0.1778 0.2794)
						)
						(arc
							(start 0.1778 0.2794)
							(mid 0.249642 0.249642)
							(end 0.2794 0.1778)
						)
						(arc
							(start 0.2794 -0.1778)
							(mid 0.249642 -0.249642)
							(end 0.1778 -0.2794)
						)
					)
					(width 0)
					(fill yes)
				)
			)
		)
	)
	(footprint ""
		(layer "F.Cu")
		(at 268.608048 -212.420454 180)
		(property "Reference" "C104"
			(at 0 0 180)
			(layer "F.SilkS")
			(hide yes)
			(effects
				(font
					(size 1.27 1.27)
				)
			)
		)
		(property "Value" "SCD22U10V2KX-1GP"
			(at 1.1811 -2.7051 180)
			(unlocked yes)
			(layer "F.Fab")
			(hide yes)
			(effects
				(font
					(size 1.016 1.016)
					(thickness 0.1524)
				)
			)
		)
		(property "Device Type" "C402H22"
			(at 1.1811 -4.2291 180)
			(unlocked yes)
			(layer "F.Fab")
			(hide yes)
			(effects
				(font
					(size 1.016 1.016)
					(thickness 0.1524)
				)
			)
		)
		(duplicate_pad_numbers_are_jumpers no)
		(fp_rect
			(start -0.4318 0.9525)
			(end 0.4318 -0.9525)
			(stroke
				(width 0)
				(type default)
			)
			(fill no)
			(layer "F.CrtYd")
		)
		(fp_rect
			(start -0.4318 0.9525)
			(end 0.4318 -0.9525)
			(stroke
				(width 0)
				(type default)
			)
			(fill no)
			(layer "F.Fab")
		)
		(pad "1" smd custom
			(at 0 -0.4445 180)
			(size 0.1524 0.1524)
			(layers "F.Cu" "F.Mask" "F.Paste")
			(net "PCIE_TX_CAP_N36")
			(options
				(clearance outline)
				(anchor circle)
			)
			(primitives
				(gr_poly
					(pts
						(arc
							(start 0.3048 -0.2032)
							(mid 0.275042 -0.275042)
							(end 0.2032 -0.3048)
						)
						(arc
							(start -0.2032 -0.3048)
							(mid -0.275042 -0.275042)
							(end -0.3048 -0.2032)
						)
						(arc
							(start -0.3048 0.2032)
							(mid -0.275042 0.275042)
							(end -0.2032 0.3048)
						)
						(arc
							(start 0.2032 0.3048)
							(mid 0.275042 0.275042)
							(end 0.3048 0.2032)
						)
					)
					(width 0)
					(fill yes)
				)
			)
		)
		(pad "2" smd custom
			(at 0 0.4445 180)
			(size 0.1524 0.1524)
			(layers "F.Cu" "F.Mask" "F.Paste")
			(net "PCIE_TX_N36")
			(options
				(clearance outline)
				(anchor circle)
			)
			(primitives
				(gr_poly
					(pts
						(arc
							(start 0.3048 -0.2032)
							(mid 0.275042 -0.275042)
							(end 0.2032 -0.3048)
						)
						(arc
							(start -0.2032 -0.3048)
							(mid -0.275042 -0.275042)
							(end -0.3048 -0.2032)
						)
						(arc
							(start -0.3048 0.2032)
							(mid -0.275042 0.275042)
							(end -0.2032 0.3048)
						)
						(arc
							(start 0.2032 0.3048)
							(mid 0.275042 0.275042)
							(end 0.3048 0.2032)
						)
					)
					(width 0)
					(fill yes)
				)
			)
		)
	)
	(footprint ""
		(layer "F.Cu")
		(at 191.5922 -13.6652 -90)
		(property "Reference" "R544"
			(at 0 0 270)
			(layer "F.SilkS")
			(hide yes)
			(effects
				(font
					(size 1.27 1.27)
				)
			)
		)
		(property "Value" "1KR2F-3-GP"
			(at 0.064008 -3.993896 270)
			(unlocked yes)
			(layer "F.Fab")
			(hide yes)
			(effects
				(font
					(size 1.016 1.016)
					(thickness 0.1524)
				)
			)
		)
		(property "Device Type" "R402H16"
			(at 0.064008 -5.517896 270)
			(unlocked yes)
			(layer "F.Fab")
			(hide yes)
			(effects
				(font
					(size 1.016 1.016)
					(thickness 0.1524)
				)
			)
		)
		(duplicate_pad_numbers_are_jumpers no)
		(fp_line
			(start -0.508 -0.9398)
			(end -0.508 0.9398)
			(stroke
				(width 0.1524)
				(type default)
			)
			(layer "F.SilkS")
		)
		(fp_line
			(start 0.508 -0.9398)
			(end -0.508 -0.9398)
			(stroke
				(width 0.1524)
				(type default)
			)
			(layer "F.SilkS")
		)
		(fp_rect
			(start -0.508 0.9398)
			(end 0.508 -0.9398)
			(stroke
				(width 0)
				(type default)
			)
			(fill no)
			(layer "F.CrtYd")
		)
		(fp_rect
			(start -0.508 0.9398)
			(end 0.508 -0.9398)
			(stroke
				(width 0)
				(type default)
			)
			(fill no)
			(layer "F.Fab")
		)
		(pad "1" smd custom
			(at 0 -0.4445 270)
			(size 0.1397 0.1397)
			(layers "F.Cu" "F.Mask" "F.Paste")
			(net "ENCLO_LED_RED_D")
			(options
				(clearance outline)
				(anchor circle)
			)
			(primitives
				(gr_poly
					(pts
						(arc
							(start -0.1778 -0.2794)
							(mid -0.249642 -0.249642)
							(end -0.2794 -0.1778)
						)
						(arc
							(start -0.2794 0.1778)
							(mid -0.249642 0.249642)
							(end -0.1778 0.2794)
						)
						(arc
							(start 0.1778 0.2794)
							(mid 0.249642 0.249642)
							(end 0.2794 0.1778)
						)
						(arc
							(start 0.2794 -0.1778)
							(mid 0.249642 -0.249642)
							(end 0.1778 -0.2794)
						)
					)
					(width 0)
					(fill yes)
				)
			)
		)
		(pad "2" smd custom
			(at 0 0.4445 270)
			(size 0.1397 0.1397)
			(layers "F.Cu" "F.Mask" "F.Paste")
			(net "P3V3_STBY")
			(options
				(clearance outline)
				(anchor circle)
			)
			(primitives
				(gr_poly
					(pts
						(arc
							(start -0.1778 -0.2794)
							(mid -0.249642 -0.249642)
							(end -0.2794 -0.1778)
						)
						(arc
							(start -0.2794 0.1778)
							(mid -0.249642 0.249642)
							(end -0.1778 0.2794)
						)
						(arc
							(start 0.1778 0.2794)
							(mid 0.249642 0.249642)
							(end 0.2794 0.1778)
						)
						(arc
							(start 0.2794 -0.1778)
							(mid 0.249642 -0.249642)
							(end 0.1778 -0.2794)
						)
					)
					(width 0)
					(fill yes)
				)
			)
		)
	)
	(footprint ""
		(layer "F.Cu")
		(at 276.50948 -6.96976 90)
		(property "Reference" "R2912"
			(at 0 0 90)
			(layer "F.SilkS")
			(hide yes)
			(effects
				(font
					(size 1.27 1.27)
				)
			)
		)
		(property "Value" "0R2J-2-GP"
			(at 0.064008 -3.993896 90)
			(unlocked yes)
			(layer "F.Fab")
			(hide yes)
			(effects
				(font
					(size 1.016 1.016)
					(thickness 0.1524)
				)
			)
		)
		(property "Device Type" "R402H16"
			(at 0.064008 -5.517896 90)
			(unlocked yes)
			(layer "F.Fab")
			(hide yes)
			(effects
				(font
					(size 1.016 1.016)
					(thickness 0.1524)
				)
			)
		)
		(duplicate_pad_numbers_are_jumpers no)
		(fp_line
			(start 0.508 -0.9398)
			(end -0.508 -0.9398)
			(stroke
				(width 0.1524)
				(type default)
			)
			(layer "F.SilkS")
		)
		(fp_line
			(start -0.508 -0.9398)
			(end -0.508 0.9398)
			(stroke
				(width 0.1524)
				(type default)
			)
			(layer "F.SilkS")
		)
		(fp_rect
			(start -0.508 0.9398)
			(end 0.508 -0.9398)
			(stroke
				(width 0)
				(type default)
			)
			(fill no)
			(layer "F.CrtYd")
		)
		(fp_rect
			(start -0.508 0.9398)
			(end 0.508 -0.9398)
			(stroke
				(width 0)
				(type default)
			)
			(fill no)
			(layer "F.Fab")
		)
		(pad "1" smd custom
			(at 0 -0.4445 90)
			(size 0.1397 0.1397)
			(layers "F.Cu" "F.Mask" "F.Paste")
			(net "BMC_I2C12_MINI6_SDA")
			(options
				(clearance outline)
				(anchor circle)
			)
			(primitives
				(gr_poly
					(pts
						(arc
							(start -0.1778 -0.2794)
							(mid -0.249642 -0.249642)
							(end -0.2794 -0.1778)
						)
						(arc
							(start -0.2794 0.1778)
							(mid -0.249642 0.249642)
							(end -0.1778 0.2794)
						)
						(arc
							(start 0.1778 0.2794)
							(mid 0.249642 0.249642)
							(end 0.2794 0.1778)
						)
						(arc
							(start 0.2794 -0.1778)
							(mid 0.249642 -0.249642)
							(end 0.1778 -0.2794)
						)
					)
					(width 0)
					(fill yes)
				)
			)
		)
		(pad "2" smd custom
			(at 0 0.4445 90)
			(size 0.1397 0.1397)
			(layers "F.Cu" "F.Mask" "F.Paste")
			(net "8644_CBL_PRSNT_R_6")
			(options
				(clearance outline)
				(anchor circle)
			)
			(primitives
				(gr_poly
					(pts
						(arc
							(start -0.1778 -0.2794)
							(mid -0.249642 -0.249642)
							(end -0.2794 -0.1778)
						)
						(arc
							(start -0.2794 0.1778)
							(mid -0.249642 0.249642)
							(end -0.1778 0.2794)
						)
						(arc
							(start 0.1778 0.2794)
							(mid 0.249642 0.249642)
							(end 0.2794 0.1778)
						)
						(arc
							(start 0.2794 -0.1778)
							(mid 0.249642 -0.249642)
							(end 0.1778 -0.2794)
						)
					)
					(width 0)
					(fill yes)
				)
			)
		)
	)
	(footprint ""
		(layer "F.Cu")
		(at 310.007 -57.1246)
		(property "Reference" "PG60"
			(at 0 0 0)
			(layer "F.SilkS")
			(hide yes)
			(effects
				(font
					(size 1.27 1.27)
				)
			)
		)
		(property "Value" "GAP-CLOSE-PWR-3-GP"
			(at 0.0254 -6.5786 0)
			(unlocked yes)
			(layer "F.Fab")
			(hide yes)
			(effects
				(font
					(size 1.016 1.016)
					(thickness 0.1524)
				)
			)
		)
		(property "Device Type" "GAP-CLOSE-PWR-3"
			(at 0.0254 -8.255 0)
			(unlocked yes)
			(layer "F.Fab")
			(hide yes)
			(effects
				(font
					(size 1.016 1.016)
					(thickness 0.1524)
				)
			)
		)
		(duplicate_pad_numbers_are_jumpers no)
		(fp_rect
			(start -0.7112 0.4572)
			(end 0.7112 -0.4572)
			(stroke
				(width 0)
				(type default)
			)
			(fill no)
			(layer "F.CrtYd")
		)
		(fp_poly
			(pts
				(xy -0.7112 -0.4572) (xy 0.7112 -0.4572) (xy 0.7112 0.4572) (xy -0.7112 0.4572)
			)
			(stroke
				(width 0)
				(type default)
			)
			(fill no)
			(layer "F.Fab")
		)
		(pad "1" smd rect
			(at -0.3048 0)
			(size 0.6604 0.762)
			(layers "F.Cu" "F.Mask" "F.Paste")
			(net "DUT_VDD")
		)
		(pad "2" smd rect
			(at 0.3048 0)
			(size 0.6604 0.762)
			(layers "F.Cu" "F.Mask" "F.Paste")
			(net "P0V9_E")
		)
	)
	(footprint ""
		(layer "F.Cu")
		(at 10.541 -66.929 180)
		(property "Reference" "C623"
			(at 0 0 180)
			(layer "F.SilkS")
			(hide yes)
			(effects
				(font
					(size 1.27 1.27)
				)
			)
		)
		(property "Value" "SCD1U16V2KX-3GP"
			(at 1.1811 -2.7051 180)
			(unlocked yes)
			(layer "F.Fab")
			(hide yes)
			(effects
				(font
					(size 1.016 1.016)
					(thickness 0.1524)
				)
			)
		)
		(property "Device Type" "C402H22"
			(at 1.1811 -4.2291 180)
			(unlocked yes)
			(layer "F.Fab")
			(hide yes)
			(effects
				(font
					(size 1.016 1.016)
					(thickness 0.1524)
				)
			)
		)
		(duplicate_pad_numbers_are_jumpers no)
		(fp_rect
			(start -0.4318 0.9525)
			(end 0.4318 -0.9525)
			(stroke
				(width 0)
				(type default)
			)
			(fill no)
			(layer "F.CrtYd")
		)
		(fp_rect
			(start -0.4318 0.9525)
			(end 0.4318 -0.9525)
			(stroke
				(width 0)
				(type default)
			)
			(fill no)
			(layer "F.Fab")
		)
		(pad "1" smd custom
			(at 0 -0.4445 180)
			(size 0.1524 0.1524)
			(layers "F.Cu" "F.Mask" "F.Paste")
			(net "P1V5_I210")
			(options
				(clearance outline)
				(anchor circle)
			)
			(primitives
				(gr_poly
					(pts
						(arc
							(start 0.3048 -0.2032)
							(mid 0.275042 -0.275042)
							(end 0.2032 -0.3048)
						)
						(arc
							(start -0.2032 -0.3048)
							(mid -0.275042 -0.275042)
							(end -0.3048 -0.2032)
						)
						(arc
							(start -0.3048 0.2032)
							(mid -0.275042 0.275042)
							(end -0.2032 0.3048)
						)
						(arc
							(start 0.2032 0.3048)
							(mid 0.275042 0.275042)
							(end 0.3048 0.2032)
						)
					)
					(width 0)
					(fill yes)
				)
			)
		)
		(pad "2" smd custom
			(at 0 0.4445 180)
			(size 0.1524 0.1524)
			(layers "F.Cu" "F.Mask" "F.Paste")
			(net "GND")
			(options
				(clearance outline)
				(anchor circle)
			)
			(primitives
				(gr_poly
					(pts
						(arc
							(start 0.3048 -0.2032)
							(mid 0.275042 -0.275042)
							(end 0.2032 -0.3048)
						)
						(arc
							(start -0.2032 -0.3048)
							(mid -0.275042 -0.275042)
							(end -0.3048 -0.2032)
						)
						(arc
							(start -0.3048 0.2032)
							(mid -0.275042 0.275042)
							(end -0.2032 0.3048)
						)
						(arc
							(start 0.2032 0.3048)
							(mid 0.275042 0.275042)
							(end 0.3048 0.2032)
						)
					)
					(width 0)
					(fill yes)
				)
			)
		)
	)
	(footprint ""
		(layer "F.Cu")
		(at 330.740512 -184.878218)
		(property "Reference" "R7920"
			(at 0 0 0)
			(layer "F.SilkS")
			(hide yes)
			(effects
				(font
					(size 1.27 1.27)
				)
			)
		)
		(property "Value" "0R2J-2-GP"
			(at 0.064008 -3.993896 0)
			(unlocked yes)
			(layer "F.Fab")
			(hide yes)
			(effects
				(font
					(size 1.016 1.016)
					(thickness 0.1524)
				)
			)
		)
		(property "Device Type" "R402H16"
			(at 0.064008 -5.517896 0)
			(unlocked yes)
			(layer "F.Fab")
			(hide yes)
			(effects
				(font
					(size 1.016 1.016)
					(thickness 0.1524)
				)
			)
		)
		(duplicate_pad_numbers_are_jumpers no)
		(fp_line
			(start -0.508 -0.9398)
			(end -0.508 0.9398)
			(stroke
				(width 0.1524)
				(type default)
			)
			(layer "F.SilkS")
		)
		(fp_line
			(start 0.508 -0.9398)
			(end -0.508 -0.9398)
			(stroke
				(width 0.1524)
				(type default)
			)
			(layer "F.SilkS")
		)
		(fp_rect
			(start -0.508 0.9398)
			(end 0.508 -0.9398)
			(stroke
				(width 0)
				(type default)
			)
			(fill no)
			(layer "F.CrtYd")
		)
		(fp_rect
			(start -0.508 0.9398)
			(end 0.508 -0.9398)
			(stroke
				(width 0)
				(type default)
			)
			(fill no)
			(layer "F.Fab")
		)
		(pad "1" smd custom
			(at 0 -0.4445)
			(size 0.1397 0.1397)
			(layers "F.Cu" "F.Mask" "F.Paste")
			(net "TWI_SDA1")
			(options
				(clearance outline)
				(anchor circle)
			)
			(primitives
				(gr_poly
					(pts
						(arc
							(start -0.1778 -0.2794)
							(mid -0.249642 -0.249642)
							(end -0.2794 -0.1778)
						)
						(arc
							(start -0.2794 0.1778)
							(mid -0.249642 0.249642)
							(end -0.1778 0.2794)
						)
						(arc
							(start 0.1778 0.2794)
							(mid 0.249642 0.249642)
							(end 0.2794 0.1778)
						)
						(arc
							(start 0.2794 -0.1778)
							(mid 0.249642 -0.249642)
							(end 0.1778 -0.2794)
						)
					)
					(width 0)
					(fill yes)
				)
			)
		)
		(pad "2" smd custom
			(at 0 0.4445)
			(size 0.1397 0.1397)
			(layers "F.Cu" "F.Mask" "F.Paste")
			(net "I2C_GPIO_SDA_4")
			(options
				(clearance outline)
				(anchor circle)
			)
			(primitives
				(gr_poly
					(pts
						(arc
							(start -0.1778 -0.2794)
							(mid -0.249642 -0.249642)
							(end -0.2794 -0.1778)
						)
						(arc
							(start -0.2794 0.1778)
							(mid -0.249642 0.249642)
							(end -0.1778 0.2794)
						)
						(arc
							(start 0.1778 0.2794)
							(mid 0.249642 0.249642)
							(end 0.2794 0.1778)
						)
						(arc
							(start 0.2794 -0.1778)
							(mid 0.249642 -0.249642)
							(end 0.1778 -0.2794)
						)
					)
					(width 0)
					(fill yes)
				)
			)
		)
	)
	(footprint ""
		(layer "F.Cu")
		(at 79.097124 -195.681092 180)
		(property "Reference" "R7948"
			(at 0 0 180)
			(layer "F.SilkS")
			(hide yes)
			(effects
				(font
					(size 1.27 1.27)
				)
			)
		)
		(property "Value" "0R2J-2-GP"
			(at 0.064008 -3.993896 180)
			(unlocked yes)
			(layer "F.Fab")
			(hide yes)
			(effects
				(font
					(size 1.016 1.016)
					(thickness 0.1524)
				)
			)
		)
		(property "Device Type" "R402H16"
			(at 0.064008 -5.517896 180)
			(unlocked yes)
			(layer "F.Fab")
			(hide yes)
			(effects
				(font
					(size 1.016 1.016)
					(thickness 0.1524)
				)
			)
		)
		(duplicate_pad_numbers_are_jumpers no)
		(fp_line
			(start 0.508 -0.9398)
			(end -0.508 -0.9398)
			(stroke
				(width 0.1524)
				(type default)
			)
			(layer "F.SilkS")
		)
		(fp_line
			(start -0.508 -0.9398)
			(end -0.508 0.9398)
			(stroke
				(width 0.1524)
				(type default)
			)
			(layer "F.SilkS")
		)
		(fp_rect
			(start -0.508 0.9398)
			(end 0.508 -0.9398)
			(stroke
				(width 0)
				(type default)
			)
			(fill no)
			(layer "F.CrtYd")
		)
		(fp_rect
			(start -0.508 0.9398)
			(end 0.508 -0.9398)
			(stroke
				(width 0)
				(type default)
			)
			(fill no)
			(layer "F.Fab")
		)
		(pad "1" smd custom
			(at 0 -0.4445 180)
			(size 0.1397 0.1397)
			(layers "F.Cu" "F.Mask" "F.Paste")
			(net "SSD_ATNLED#10")
			(options
				(clearance outline)
				(anchor circle)
			)
			(primitives
				(gr_poly
					(pts
						(arc
							(start -0.1778 -0.2794)
							(mid -0.249642 -0.249642)
							(end -0.2794 -0.1778)
						)
						(arc
							(start -0.2794 0.1778)
							(mid -0.249642 0.249642)
							(end -0.1778 0.2794)
						)
						(arc
							(start 0.1778 0.2794)
							(mid 0.249642 0.249642)
							(end 0.2794 0.1778)
						)
						(arc
							(start 0.2794 -0.1778)
							(mid 0.249642 -0.249642)
							(end 0.1778 -0.2794)
						)
					)
					(width 0)
					(fill yes)
				)
			)
		)
		(pad "2" smd custom
			(at 0 0.4445 180)
			(size 0.1397 0.1397)
			(layers "F.Cu" "F.Mask" "F.Paste")
			(net "SSD_ATNLED#10_R")
			(options
				(clearance outline)
				(anchor circle)
			)
			(primitives
				(gr_poly
					(pts
						(arc
							(start -0.1778 -0.2794)
							(mid -0.249642 -0.249642)
							(end -0.2794 -0.1778)
						)
						(arc
							(start -0.2794 0.1778)
							(mid -0.249642 0.249642)
							(end -0.1778 0.2794)
						)
						(arc
							(start 0.1778 0.2794)
							(mid 0.249642 0.249642)
							(end 0.2794 0.1778)
						)
						(arc
							(start 0.2794 -0.1778)
							(mid 0.249642 -0.249642)
							(end 0.1778 -0.2794)
						)
					)
					(width 0)
					(fill yes)
				)
			)
		)
	)
)
